#ISCELL
  pure_quanta quanta_title_block_c *
  *
#ISCELL
  standard offpage *
  page22_i1
#ISCELL
  standard tap *
  page22_i10
#ISCELL
  standard tap *
  page22_i100
#ISCELL
  standard tap *
  page22_i101
#ISCELL
  standard tap *
  page22_i102
#ISCELL
  standard tap *
  page22_i103
#ISCELL
  standard tap *
  page22_i104
#ISCELL
  standard tap *
  page22_i105
#ISCELL
  standard tap *
  page22_i106
#ISCELL
  standard tap *
  page22_i107
#ISCELL
  standard tap *
  page22_i108
#ISCELL
  standard tap *
  page22_i109
#ISCELL
  standard tap *
  page22_i11
#ISCELL
  standard tap *
  page22_i110
#ISCELL
  standard tap *
  page22_i111
#ISCELL
  standard tap *
  page22_i112
#ISCELL
  standard tap *
  page22_i113
#ISCELL
  standard tap *
  page22_i114
#ISCELL
  standard tap *
  page22_i115
#ISCELL
  standard tap *
  page22_i116
#ISCELL
  standard tap *
  page22_i117
#ISCELL
  standard tap *
  page22_i118
#ISCELL
  standard tap *
  page22_i119
#ISCELL
  standard tap *
  page22_i12
#ISCELL
  standard tap *
  page22_i120
#ISCELL
  standard tap *
  page22_i121
#ISCELL
  standard tap *
  page22_i122
#ISCELL
  standard tap *
  page22_i123
#ISCELL
  standard tap *
  page22_i124
#ISCELL
  standard tap *
  page22_i125
#ISCELL
  standard tap *
  page22_i126
#ISCELL
  standard tap *
  page22_i127
#ISCELL
  standard tap *
  page22_i128
#ISCELL
  standard tap *
  page22_i129
#ISCELL
  standard tap *
  page22_i13
#ISCELL
  standard tap *
  page22_i130
#ISCELL
  standard tap *
  page22_i131
#ISCELL
  standard tap *
  page22_i132
#ISCELL
  standard tap *
  page22_i133
#ISCELL
  standard tap *
  page22_i134
#ISCELL
  standard tap *
  page22_i135
#ISCELL
  standard tap *
  page22_i136
#ISCELL
  standard tap *
  page22_i137
#ISCELL
  standard tap *
  page22_i138
#ISCELL
  standard tap *
  page22_i139
#ISCELL
  standard tap *
  page22_i14
#ISCELL
  standard tap *
  page22_i140
#ISCELL
  standard tap *
  page22_i141
#ISCELL
  standard tap *
  page22_i142
#ISCELL
  standard tap *
  page22_i143
#ISCELL
  standard tap *
  page22_i144
#ISCELL
  standard tap *
  page22_i145
#ISCELL
  standard tap *
  page22_i146
#ISCELL
  standard tap *
  page22_i147
#ISCELL
  standard tap *
  page22_i148
#ISCELL
  standard tap *
  page22_i149
#ISCELL
  standard tap *
  page22_i15
#ISCELL
  standard tap *
  page22_i150
#ISCELL
  standard tap *
  page22_i151
#ISCELL
  standard tap *
  page22_i152
#ISCELL
  standard tap *
  page22_i153
#ISCELL
  standard tap *
  page22_i154
#ISCELL
  standard tap *
  page22_i155
#ISCELL
  standard tap *
  page22_i156
#ISCELL
  standard tap *
  page22_i157
#ISCELL
  standard offpage *
  page22_i158
#ISCELL
  standard offpage *
  page22_i159
#ISCELL
  standard tap *
  page22_i16
#ISCELL
  standard offpage *
  page22_i160
#ISCELL
  standard offpage *
  page22_i161
#ISCELL
  standard offpage *
  page22_i162
#ISCELL
  standard offpage *
  page22_i163
#ISCELL
  standard offpage *
  page22_i164
#ISCELL
  standard offpage *
  page22_i165
#ISCELL
  standard offpage *
  page22_i166
#ISCELL
  standard offpage *
  page22_i167
#ISCELL
  standard offpage *
  page22_i168
#CELL
  pure_quanta socket4677_azif0045p001c01cs *
  page22_i169
#ISCELL
  standard tap *
  page22_i17
#ISCELL
  standard tap *
  page22_i18
#ISCELL
  standard tap *
  page22_i19
#ISCELL
  standard offpage *
  page22_i2
#ISCELL
  standard tap *
  page22_i20
#ISCELL
  standard tap *
  page22_i21
#ISCELL
  standard tap *
  page22_i22
#ISCELL
  standard tap *
  page22_i23
#ISCELL
  standard tap *
  page22_i24
#ISCELL
  standard tap *
  page22_i25
#ISCELL
  standard tap *
  page22_i26
#ISCELL
  standard tap *
  page22_i27
#ISCELL
  standard tap *
  page22_i28
#ISCELL
  standard tap *
  page22_i29
#ISCELL
  standard tap *
  page22_i3
#ISCELL
  standard tap *
  page22_i30
#ISCELL
  standard tap *
  page22_i31
#ISCELL
  standard tap *
  page22_i32
#ISCELL
  standard tap *
  page22_i33
#ISCELL
  standard tap *
  page22_i34
#ISCELL
  standard tap *
  page22_i35
#ISCELL
  standard tap *
  page22_i36
#ISCELL
  standard tap *
  page22_i37
#ISCELL
  standard tap *
  page22_i38
#ISCELL
  standard tap *
  page22_i39
#ISCELL
  standard tap *
  page22_i4
#ISCELL
  standard tap *
  page22_i40
#ISCELL
  standard tap *
  page22_i41
#ISCELL
  standard tap *
  page22_i42
#ISCELL
  standard tap *
  page22_i43
#ISCELL
  standard tap *
  page22_i44
#ISCELL
  standard tap *
  page22_i45
#ISCELL
  standard tap *
  page22_i46
#ISCELL
  standard tap *
  page22_i47
#ISCELL
  standard tap *
  page22_i48
#ISCELL
  standard tap *
  page22_i49
#ISCELL
  standard tap *
  page22_i5
#ISCELL
  standard offpage *
  page22_i50
#ISCELL
  standard offpage *
  page22_i51
#ISCELL
  standard tap *
  page22_i52
#ISCELL
  standard tap *
  page22_i53
#ISCELL
  standard tap *
  page22_i54
#ISCELL
  standard tap *
  page22_i55
#ISCELL
  standard tap *
  page22_i56
#ISCELL
  standard tap *
  page22_i57
#ISCELL
  standard tap *
  page22_i58
#ISCELL
  standard tap *
  page22_i59
#ISCELL
  standard tap *
  page22_i6
#ISCELL
  standard tap *
  page22_i60
#ISCELL
  standard tap *
  page22_i61
#ISCELL
  standard tap *
  page22_i62
#ISCELL
  standard tap *
  page22_i63
#ISCELL
  standard tap *
  page22_i64
#ISCELL
  standard tap *
  page22_i65
#ISCELL
  standard tap *
  page22_i66
#ISCELL
  standard tap *
  page22_i67
#ISCELL
  standard tap *
  page22_i68
#ISCELL
  standard tap *
  page22_i69
#ISCELL
  standard offpage *
  page22_i7
#ISCELL
  standard tap *
  page22_i70
#ISCELL
  standard tap *
  page22_i71
#ISCELL
  standard tap *
  page22_i72
#ISCELL
  standard tap *
  page22_i73
#ISCELL
  standard tap *
  page22_i74
#ISCELL
  standard tap *
  page22_i75
#ISCELL
  standard tap *
  page22_i76
#ISCELL
  standard tap *
  page22_i77
#ISCELL
  standard tap *
  page22_i78
#ISCELL
  standard tap *
  page22_i79
#ISCELL
  standard offpage *
  page22_i8
#ISCELL
  standard tap *
  page22_i80
#ISCELL
  standard tap *
  page22_i81
#ISCELL
  standard tap *
  page22_i82
#ISCELL
  standard tap *
  page22_i83
#ISCELL
  standard tap *
  page22_i84
#ISCELL
  standard tap *
  page22_i85
#ISCELL
  standard tap *
  page22_i86
#ISCELL
  standard tap *
  page22_i87
#ISCELL
  standard tap *
  page22_i88
#ISCELL
  standard tap *
  page22_i89
#ISCELL
  standard tap *
  page22_i9
#ISCELL
  standard tap *
  page22_i90
#ISCELL
  standard offpage *
  page22_i92
#ISCELL
  standard offpage *
  page22_i93
#ISCELL
  standard offpage *
  page22_i94
#ISCELL
  standard offpage *
  page22_i95
#ISCELL
  standard tap *
  page22_i96
#ISCELL
  standard tap *
  page22_i97
#ISCELL
  standard tap *
  page22_i98
#ISCELL
  standard tap *
  page22_i99
